# S9S_MB_2U (Grand Teton) — schematic netlist excerpt (pin names and nets, part order shuffled) for the footprints in the layout excerpt that follows; sources: Cadence DE-HDL packaged netlist, KiCad conversion of 03242023_DA0F0TMBIJ0_F0T_Motherboard_J_brd_V01_OCP.brd

J6  SCONN288_ADR50017P087CC  SCONN288_ADR50017-P087CC IO  pkg DDR288S_1-1VXB  page 87
  VIN_BULK0  = P12V_S3_AUX_CPU0_NVDIMM
  RFU0  = TP_CHC_CPU0_DIMM2_FRU_0
  VIN_MGMT  = P3V3_AUX
  HSCL  = I3C_SPD_DDRABCD_CPU0_LVC1_SCL_5
  HSDA  = I3C_SPD_DDRABCD_CPU0_LVC1_SDA
  VSS0  = GND
  DQ0_A  = M_C_CPU0_SA_DQ<0>
  VSS1  = GND
  DQ1_A  = M_C_CPU0_SA_DQ<1>
  VSS2  = GND
  DQS0_A_T  = M_C_CPU0_SA_DQS_DP<0>
  DQS0_A_C  = M_C_CPU0_SA_DQS_DN<0>
  VSS3  = GND
  DQ4_A  = M_C_CPU0_SA_DQ<4>
  VSS4  = GND
  DQ5_A  = M_C_CPU0_SA_DQ<5>
  VSS5  = GND
  DQ8_A  = M_C_CPU0_SA_DQ<8>
  VSS6  = GND
  DQ9_A  = M_C_CPU0_SA_DQ<9>
  VSS7  = GND
  DQS1_A_T  = M_C_CPU0_SA_DQS_DP<1>
  DQS1_A_C  = M_C_CPU0_SA_DQS_DN<1>
  VSS8  = GND
  DQ12_A  = M_C_CPU0_SA_DQ<12>
  VSS9  = GND
  DQ13_A  = M_C_CPU0_SA_DQ<13>
  VSS10  = GND
  DQ16_A  = M_C_CPU0_SA_DQ<16>
  VSS11  = GND
  DQ17_A  = M_C_CPU0_SA_DQ<17>
  VSS12  = GND
  DQS2_A_T  = M_C_CPU0_SA_DQS_DP<2>
  DQS2_A_C  = M_C_CPU0_SA_DQS_DN<2>
  VSS13  = GND
  DQ20_A  = M_C_CPU0_SA_DQ<20>
  VSS14  = GND
  DQ21_A  = M_C_CPU0_SA_DQ<21>
  VSS15  = GND
  DQ24_A  = M_C_CPU0_SA_DQ<24>
  VSS16  = GND
  DQ25_A  = M_C_CPU0_SA_DQ<25>
  VSS17  = GND
  DQS3_A_T  = M_C_CPU0_SA_DQS_DP<3>
  DQS3_A_C  = M_C_CPU0_SA_DQS_DN<3>
  VSS18  = GND
  DQ28_A  = M_C_CPU0_SA_DQ<28>
  VSS19  = GND
  DQ29_A  = M_C_CPU0_SA_DQ<29>
  VSS20  = GND
  CB0_A  = M_C_CPU0_SA_CB<0>
  VSS21  = GND
  CB1_A  = M_C_CPU0_SA_CB<1>
  VSS22  = GND
  DQS4_A_T  = M_C_CPU0_SA_DQS_DP<4>
  DQS4_A_C  = M_C_CPU0_SA_DQS_DN<4>
  VSS23  = GND
  CB4_A  = M_C_CPU0_SA_CB<4>
  VSS24  = GND
  CB5_A  = M_C_CPU0_SA_CB<5>
  VSS25  = GND
  ALERT_N  = M_C_CPU0_ALERT_N
  VSS26  = GND
  CS0_A_N  = M_C_CPU0_SA_CS_N<2>
  VSS27  = GND
  CA0_A  = M_C_CPU0_SA_CA<0>
  VSS28  = GND
  CA2_A  = M_C_CPU0_SA_CA<2>
  VSS29  = GND
  CA4_A  = M_C_CPU0_SA_CA<4>
  VSS30  = GND
  CA6_A  = M_C_CPU0_SA_CA<6>
  VSS31  = GND
  PAR_A  = M_C_CPU0_SA_PAR
  VSS32  = GND
  CA0_B  = M_C_CPU0_SB_CA<0>
  VSS33  = GND
  CA2_B  = M_C_CPU0_SB_CA<2>
  VSS34  = GND
  CA4_B  = M_C_CPU0_SB_CA<4>
  VSS35  = GND
  CA6_B  = M_C_CPU0_SB_CA<6>
  VSS36  = GND
  CS0_B_N  = M_C_CPU0_SB_CS_N<2>
  VSS37  = GND
  \lbd||rsp_a_n\  = M_C_CPU0_SA_RSP<1>
  \lbs||rsp_b_n\  = M_C_CPU0_SB_RSP<1>
  VSS38  = GND
  CB4_B  = M_C_CPU0_SB_CB<4>
  VSS39  = GND
  CB5_B  = M_C_CPU0_SB_CB<5>
  VSS40  = GND
  \dqs9_b_t||tdqs9_b_t||dbi4_b_n\  = M_C_CPU0_SB_DQS_DP<9>
  \dqs9_b_c||tdqs9_b_c\  = M_C_CPU0_SB_DQS_DN<9>
  VSS41  = GND
  CB0_B  = M_C_CPU0_SB_CB<0>
  VSS42  = GND
  CB1_B  = M_C_CPU0_SB_CB<1>
  VSS43  = GND
  DQ0_B  = M_C_CPU0_SB_DQ<0>
  VSS44  = GND
  DQ1_B  = M_C_CPU0_SB_DQ<1>
  VSS45  = GND
  DQS0_B_T  = M_C_CPU0_SB_DQS_DP<0>
  DQS0_B_C  = M_C_CPU0_SB_DQS_DN<0>
  VSS46  = GND
  DQ4_B  = M_C_CPU0_SB_DQ<4>
  VSS47  = GND
  DQ5_B  = M_C_CPU0_SB_DQ<5>
  VSS48  = GND
  DQ8_B  = M_C_CPU0_SB_DQ<8>
  VSS49  = GND
  DQ9_B  = M_C_CPU0_SB_DQ<9>
  VSS50  = GND
  DQS1_B_T  = M_C_CPU0_SB_DQS_DP<1>
  DQS1_B_C  = M_C_CPU0_SB_DQS_DN<1>
  VSS51  = GND
  DQ12_B  = M_C_CPU0_SB_DQ<12>
  VSS52  = GND
  DQ13_B  = M_C_CPU0_SB_DQ<13>
  VSS53  = GND
  DQ16_B  = M_C_CPU0_SB_DQ<16>
  VSS54  = GND
  DQ17_B  = M_C_CPU0_SB_DQ<17>
  VSS55  = GND
  DQS2_B_T  = M_C_CPU0_SB_DQS_DP<2>
  DQS2_B_C  = M_C_CPU0_SB_DQS_DN<2>
  VSS56  = GND
  DQ20_B  = M_C_CPU0_SB_DQ<20>
  VSS57  = GND
  DQ21_B  = M_C_CPU0_SB_DQ<21>
  VSS58  = GND
  DQ24_B  = M_C_CPU0_SB_DQ<24>
  VSS59  = GND
  DQ25_B  = M_C_CPU0_SB_DQ<25>
  VSS60  = GND
  DQS3_B_T  = M_C_CPU0_SB_DQS_DP<3>
  DQS3_B_C  = M_C_CPU0_SB_DQS_DN<3>
  VSS61  = GND
  DQ28_B  = M_C_CPU0_SB_DQ<28>
  VSS62  = GND
  DQ29_B  = M_C_CPU0_SB_DQ<29>
  VSS63  = GND
  RFU1  = TP_CHC_CPU0_DIMM2_FRU_1
  VIN_BULK1  = P12V_S3_AUX_CPU0_NVDIMM
  VIN_BULK2  = P12V_S3_AUX_CPU0_NVDIMM
  \pwr_good||fail_n\  = PWRGD_CHC_CPU0_DIMM2
  HSA  = PD_CHC_CPU0_DIMM2_SAA
  RFU2  = TP_CHC_CPU0_DIMM2_FRU_2
  RFU3  = TP_CHC_CPU0_DIMM2_FRU_3
  VSS64  = GND
  DQ2_A  = M_C_CPU0_SA_DQ<2>
  VSS65  = GND
  DQ3_A  = M_C_CPU0_SA_DQ<3>
  VSS66  = GND
  \dqs5_a_c||tdqs5_a_c||dqs5_a_t||tdqs5_a_t\  = M_C_CPU0_SA_DQS_DN<5>
  \dqs5_a_t||tdqs5_a_t\  = M_C_CPU0_SA_DQS_DP<5>
  VSS67  = GND
  DQ6_A  = M_C_CPU0_SA_DQ<6>
  VSS68  = GND
  DQ7_A  = M_C_CPU0_SA_DQ<7>
  VSS69  = GND
  DQ10_A  = M_C_CPU0_SA_DQ<10>
  VSS70  = GND
  DQ11_A  = M_C_CPU0_SA_DQ<11>
  VSS71  = GND
  \dqs6_a_c||tdqs6_a_c||dqs6_a_t||tdqs6_a_t\  = M_C_CPU0_SA_DQS_DN<6>
  \dqs6_a_t||tdqs6_a_t\  = M_C_CPU0_SA_DQS_DP<6>
  VSS72  = GND
  DQ14_A  = M_C_CPU0_SA_DQ<14>
  VSS73  = GND
  DQ15_A  = M_C_CPU0_SA_DQ<15>
  VSS74  = GND
  DQ18_A  = M_C_CPU0_SA_DQ<18>
  VSS75  = GND
  DQ19_A  = M_C_CPU0_SA_DQ<19>
  VSS76  = GND
  \dqs7_a_c||tdqs7_a_c\  = M_C_CPU0_SA_DQS_DN<7>
  \dqs7_a_t||tdqs7_a_t\  = M_C_CPU0_SA_DQS_DP<7>
  VSS77  = GND
  DQ22_A  = M_C_CPU0_SA_DQ<22>
  VSS78  = GND
  DQ23_A  = M_C_CPU0_SA_DQ<23>
  VSS79  = GND
  DQ26_A  = M_C_CPU0_SA_DQ<26>
  VSS80  = GND
  DQ27_A  = M_C_CPU0_SA_DQ<27>
  VSS81  = GND
  \dqs8_a_c||tdqs8_a_c\  = M_C_CPU0_SA_DQS_DN<8>
  \dqs8_a_t||tdqs8_a_t\  = M_C_CPU0_SA_DQS_DP<8>
  VSS82  = GND
  DQ30_A  = M_C_CPU0_SA_DQ<30>
  VSS83  = GND
  DQ31_A  = M_C_CPU0_SA_DQ<31>
  VSS84  = GND
  CB2_A  = M_C_CPU0_SA_CB<2>
  VSS85  = GND
  CB3_A  = M_C_CPU0_SA_CB<3>
  VSS86  = GND
  \dqs9_a_c||tdqs9_a_c\  = M_C_CPU0_SA_DQS_DN<9>
  \dqs9_a_t||tdqs9_a_t\  = M_C_CPU0_SA_DQS_DP<9>
  VSS87  = GND
  CB6_A  = M_C_CPU0_SA_CB<6>
  VSS88  = GND
  CB7_A  = M_C_CPU0_SA_CB<7>
  VSS89  = GND
  RESET_N  = RST_M_CD_CPU0_FPGA_N
  VSS90  = GND
  CS1_A_N  = M_C_CPU0_SA_CS_N<3>
  VSS91  = GND
  CA1_A  = M_C_CPU0_SA_CA<1>
  VSS92  = GND
  CA3_A  = M_C_CPU0_SA_CA<3>
  VSS93  = GND
  CA5_A  = M_C_CPU0_SA_CA<5>
  VSS94  = GND
  CK_T  = M_C_CPU0_CLK_DP<1>
  CK_C  = M_C_CPU0_CLK_DN<1>
  VSS95  = GND
  RFU4  = TP_CHC_CPU0_DIMM2_FRU_4
  CA1_B  = M_C_CPU0_SB_CA<1>
  VSS96  = GND
  CA3_B  = M_C_CPU0_SB_CA<3>
  VSS97  = GND
  CA5_B  = M_C_CPU0_SB_CA<5>
  VSS98  = GND
  PAR_B  = M_C_CPU0_SB_PAR
  VSS99  = GND
  CS1_B_N  = M_C_CPU0_SB_CS_N<3>
  VSS100  = GND
  RFU5  = TP_CHC_CPU0_DIMM2_FRU_5
  RFU6  = TP_CHC_CPU0_DIMM2_FRU_6
  VSS101  = GND
  CB6_B  = M_C_CPU0_SB_CB<6>
  VSS102  = GND
  CB7_B  = M_C_CPU0_SB_CB<7>
  VSS103  = GND
  DQS4_B_C  = M_C_CPU0_SB_DQS_DN<4>
  DQS4_B_T  = M_C_CPU0_SB_DQS_DP<4>
  VSS104  = GND
  CB2_B  = M_C_CPU0_SB_CB<2>
  VSS105  = GND
  CB3_B  = M_C_CPU0_SB_CB<3>
  VSS106  = GND
  DQ2_B  = M_C_CPU0_SB_DQ<2>
  VSS107  = GND
  DQ3_B  = M_C_CPU0_SB_DQ<3>
  VSS108  = GND
  \dqs5_b_c||tdqs5_b_c\  = M_C_CPU0_SB_DQS_DN<5>
  \dqs5_b_t||tdqs5_b_t\  = M_C_CPU0_SB_DQS_DP<5>
  VSS109  = GND
  DQ6_B  = M_C_CPU0_SB_DQ<6>
  VSS110  = GND
  DQ7_B  = M_C_CPU0_SB_DQ<7>
  VSS111  = GND
  DQ10_B  = M_C_CPU0_SB_DQ<10>
  VSS112  = GND
  DQ11_B  = M_C_CPU0_SB_DQ<11>
  VSS113  = GND
  \dqs6_b_c||tdqs6_b_c\  = M_C_CPU0_SB_DQS_DN<6>
  \dqs6_b_t||tdqs6_b_t\  = M_C_CPU0_SB_DQS_DP<6>
  VSS114  = GND
  DQ14_B  = M_C_CPU0_SB_DQ<14>
  VSS115  = GND
  DQ15_B  = M_C_CPU0_SB_DQ<15>
  VSS116  = GND
  DQ18_B  = M_C_CPU0_SB_DQ<18>
  VSS117  = GND
  DQ19_B  = M_C_CPU0_SB_DQ<19>
  VSS118  = GND
  \dqs7_b_c||tdqs7_b_c\  = M_C_CPU0_SB_DQS_DN<7>
  \dqs7_b_t||tdqs7_b_t\  = M_C_CPU0_SB_DQS_DP<7>
  VSS119  = GND
  DQ22_B  = M_C_CPU0_SB_DQ<22>
  VSS120  = GND
  DQ23_B  = M_C_CPU0_SB_DQ<23>
  VSS121  = GND
  DQ26_B  = M_C_CPU0_SB_DQ<26>
  VSS122  = GND
  DQ27_B  = M_C_CPU0_SB_DQ<27>
  VSS123  = GND
  \dqs8_b_c||tdqs8_b_c\  = M_C_CPU0_SB_DQS_DN<8>
  \dqs8_b_t||tdqs8_b_t\  = M_C_CPU0_SB_DQS_DP<8>
  VSS124  = GND
  DQ30_B  = M_C_CPU0_SB_DQ<30>
  VSS125  = GND
  DQ31_B  = M_C_CPU0_SB_DQ<31>
  VSS126  = GND
  G1  = GND
  G2  = GND
  G3  = GND

(kicad_pcb
	(version 20260206)
	(generator "pcbnew")
	(generator_version "10.0")
	(general
		(thickness 1.6)
		(legacy_teardrops no)
	)
	(paper "A4")
	(title_block
		(title "03242023_DA0F0TMBIJ0_F0T_Motherboard_J_brd_V01_OCP.brd")
		(comment 1 "Grand Teton / footprint 3553 of 6105 (J6), pads 138-182 of 291")
	)
	(layers
		(0 "F.Cu" signal "TOP")
		(4 "In1.Cu" signal "GND")
		(6 "In2.Cu" signal "IN1")
		(8 "In3.Cu" signal "GND1")
		(10 "In4.Cu" signal "IN2")
		(12 "In5.Cu" signal "GND2")
		(14 "In6.Cu" signal "IN3")
		(16 "In7.Cu" signal "GND3")
		(18 "In8.Cu" signal "VCC")
		(20 "In9.Cu" signal "VCC1")
		(22 "In10.Cu" signal "GND4")
		(24 "In11.Cu" signal "IN4")
		(26 "In12.Cu" signal "GND5")
		(28 "In13.Cu" signal "IN5")
		(30 "In14.Cu" signal "GND6")
		(32 "In15.Cu" signal "IN6")
		(34 "In16.Cu" signal "GND7")
		(2 "B.Cu" signal "BOTTOM")
		(9 "F.Adhes" user "F.Adhesive")
		(11 "B.Adhes" user "B.Adhesive")
		(13 "F.Paste" user "Package Geometry/Pastemask Top")
		(15 "B.Paste" user "Package Geometry/Pastemask Bottom")
		(5 "F.SilkS" user "Ref Des/Silkscreen Top")
		(7 "B.SilkS" user "Ref Des/Silkscreen Bottom")
		(1 "F.Mask" user "Board Geometry/Soldermask Top")
		(3 "B.Mask" user "Board Geometry/Soldermask Bottom")
		(17 "Dwgs.User" user "User.Drawings")
		(19 "Cmts.User" user "User.Comments")
		(21 "Eco1.User" user "User.Eco1")
		(23 "Eco2.User" user "User.Eco2")
		(25 "Edge.Cuts" user "Board Geometry/Outline")
		(27 "Margin" user)
		(31 "F.CrtYd" user "Package Geometry/Place Bound Top")
		(29 "B.CrtYd" user "Package Geometry/Place Bound Bottom")
		(35 "F.Fab" user "Ref Des/Assembly Top")
		(33 "B.Fab" user "Ref Des/Assembly Bottom")
	)
	(footprint ""
		(layer "F.Cu")
		(at 280.761948 -258.091686)
		(property "Reference" "J6"
			(at -3.683 -81.702148 0)
			(unlocked yes)
			(layer "F.SilkS")
			(effects
				(font
					(size 0.7874 0.5842)
					(thickness 0.1524)
				)
				(justify left)
			)
		)
		(property "Value" ""
			(at 0 0 0)
			(layer "F.Fab")
			(effects
				(font
					(size 1.27 1.27)
				)
			)
		)
		(duplicate_pad_numbers_are_jumpers no)
		(pad "138" smd rect
			(at -2.050034 58.224928 270)
			(size 0.519938 1.4986)
			(layers "F.Cu" "F.Mask" "F.Paste")
			(net "M_C_CPU0_SB_DQS_DN<3>")
		)
		(pad "139" smd rect
			(at -2.050034 59.075066 270)
			(size 0.519938 1.4986)
			(layers "F.Cu" "F.Mask" "F.Paste")
			(net "GND")
		)
		(pad "140" smd rect
			(at -2.050034 59.92495 270)
			(size 0.519938 1.4986)
			(layers "F.Cu" "F.Mask" "F.Paste")
			(net "M_C_CPU0_SB_DQ<28>")
		)
		(pad "141" smd rect
			(at -2.050034 60.775088 270)
			(size 0.519938 1.4986)
			(layers "F.Cu" "F.Mask" "F.Paste")
			(net "GND")
		)
		(pad "142" smd rect
			(at -2.050034 61.624972 270)
			(size 0.519938 1.4986)
			(layers "F.Cu" "F.Mask" "F.Paste")
			(net "M_C_CPU0_SB_DQ<29>")
		)
		(pad "143" smd rect
			(at -2.050034 62.47511 270)
			(size 0.519938 1.4986)
			(layers "F.Cu" "F.Mask" "F.Paste")
			(net "GND")
		)
		(pad "144" smd rect
			(at -2.050034 63.324994 270)
			(size 0.519938 1.4986)
			(layers "F.Cu" "F.Mask" "F.Paste")
			(net "TP_CHC_CPU0_DIMM2_FRU_1")
		)
		(pad "145" smd rect
			(at 2.050034 -63.324994 270)
			(size 0.519938 1.4986)
			(layers "F.Cu" "F.Mask" "F.Paste")
			(net "P12V_S3_AUX_CPU0_NVDIMM")
		)
		(pad "146" smd rect
			(at 2.050034 -62.47511 270)
			(size 0.519938 1.4986)
			(layers "F.Cu" "F.Mask" "F.Paste")
			(net "P12V_S3_AUX_CPU0_NVDIMM")
		)
		(pad "147" smd rect
			(at 2.050034 -61.624972 270)
			(size 0.519938 1.4986)
			(layers "F.Cu" "F.Mask" "F.Paste")
			(net "PWRGD_CHC_CPU0_DIMM2")
		)
		(pad "148" smd rect
			(at 2.050034 -60.775088 270)
			(size 0.519938 1.4986)
			(layers "F.Cu" "F.Mask" "F.Paste")
			(net "PD_CHC_CPU0_DIMM2_SAA")
		)
		(pad "149" smd rect
			(at 2.050034 -59.92495 270)
			(size 0.519938 1.4986)
			(layers "F.Cu" "F.Mask" "F.Paste")
			(net "TP_CHC_CPU0_DIMM2_FRU_2")
		)
		(pad "150" smd rect
			(at 2.050034 -59.075066 270)
			(size 0.519938 1.4986)
			(layers "F.Cu" "F.Mask" "F.Paste")
			(net "TP_CHC_CPU0_DIMM2_FRU_3")
		)
		(pad "151" smd rect
			(at 2.050034 -58.224928 270)
			(size 0.519938 1.4986)
			(layers "F.Cu" "F.Mask" "F.Paste")
			(net "GND")
		)
		(pad "152" smd rect
			(at 2.050034 -57.375044 270)
			(size 0.519938 1.4986)
			(layers "F.Cu" "F.Mask" "F.Paste")
			(net "M_C_CPU0_SA_DQ<2>")
		)
		(pad "153" smd rect
			(at 2.050034 -56.524906 270)
			(size 0.519938 1.4986)
			(layers "F.Cu" "F.Mask" "F.Paste")
			(net "GND")
		)
		(pad "154" smd rect
			(at 2.050034 -55.675022 270)
			(size 0.519938 1.4986)
			(layers "F.Cu" "F.Mask" "F.Paste")
			(net "M_C_CPU0_SA_DQ<3>")
		)
		(pad "155" smd rect
			(at 2.050034 -54.824884 270)
			(size 0.519938 1.4986)
			(layers "F.Cu" "F.Mask" "F.Paste")
			(net "GND")
		)
		(pad "156" smd rect
			(at 2.050034 -53.975 270)
			(size 0.519938 1.4986)
			(layers "F.Cu" "F.Mask" "F.Paste")
			(net "M_C_CPU0_SA_DQS_DN<5>")
		)
		(pad "157" smd rect
			(at 2.050034 -53.125116 270)
			(size 0.519938 1.4986)
			(layers "F.Cu" "F.Mask" "F.Paste")
			(net "M_C_CPU0_SA_DQS_DP<5>")
		)
		(pad "158" smd rect
			(at 2.050034 -52.274978 270)
			(size 0.519938 1.4986)
			(layers "F.Cu" "F.Mask" "F.Paste")
			(net "GND")
		)
		(pad "159" smd rect
			(at 2.050034 -51.425094 270)
			(size 0.519938 1.4986)
			(layers "F.Cu" "F.Mask" "F.Paste")
			(net "M_C_CPU0_SA_DQ<6>")
		)
		(pad "160" smd rect
			(at 2.050034 -50.574956 270)
			(size 0.519938 1.4986)
			(layers "F.Cu" "F.Mask" "F.Paste")
			(net "GND")
		)
		(pad "161" smd rect
			(at 2.050034 -49.725072 270)
			(size 0.519938 1.4986)
			(layers "F.Cu" "F.Mask" "F.Paste")
			(net "M_C_CPU0_SA_DQ<7>")
		)
		(pad "162" smd rect
			(at 2.050034 -48.874934 270)
			(size 0.519938 1.4986)
			(layers "F.Cu" "F.Mask" "F.Paste")
			(net "GND")
		)
		(pad "163" smd rect
			(at 2.050034 -48.02505 270)
			(size 0.519938 1.4986)
			(layers "F.Cu" "F.Mask" "F.Paste")
			(net "M_C_CPU0_SA_DQ<10>")
		)
		(pad "164" smd rect
			(at 2.050034 -47.174912 270)
			(size 0.519938 1.4986)
			(layers "F.Cu" "F.Mask" "F.Paste")
			(net "GND")
		)
		(pad "165" smd rect
			(at 2.050034 -46.325028 270)
			(size 0.519938 1.4986)
			(layers "F.Cu" "F.Mask" "F.Paste")
			(net "M_C_CPU0_SA_DQ<11>")
		)
		(pad "166" smd rect
			(at 2.050034 -45.47489 270)
			(size 0.519938 1.4986)
			(layers "F.Cu" "F.Mask" "F.Paste")
			(net "GND")
		)
		(pad "167" smd rect
			(at 2.050034 -44.625006 270)
			(size 0.519938 1.4986)
			(layers "F.Cu" "F.Mask" "F.Paste")
			(net "M_C_CPU0_SA_DQS_DN<6>")
		)
		(pad "168" smd rect
			(at 2.050034 -43.775122 270)
			(size 0.519938 1.4986)
			(layers "F.Cu" "F.Mask" "F.Paste")
			(net "M_C_CPU0_SA_DQS_DP<6>")
		)
		(pad "169" smd rect
			(at 2.050034 -42.924984 270)
			(size 0.519938 1.4986)
			(layers "F.Cu" "F.Mask" "F.Paste")
			(net "GND")
		)
		(pad "170" smd rect
			(at 2.050034 -42.0751 270)
			(size 0.519938 1.4986)
			(layers "F.Cu" "F.Mask" "F.Paste")
			(net "M_C_CPU0_SA_DQ<14>")
		)
		(pad "171" smd rect
			(at 2.050034 -41.224962 270)
			(size 0.519938 1.4986)
			(layers "F.Cu" "F.Mask" "F.Paste")
			(net "GND")
		)
		(pad "172" smd rect
			(at 2.050034 -40.375078 270)
			(size 0.519938 1.4986)
			(layers "F.Cu" "F.Mask" "F.Paste")
			(net "M_C_CPU0_SA_DQ<15>")
		)
		(pad "173" smd rect
			(at 2.050034 -39.52494 270)
			(size 0.519938 1.4986)
			(layers "F.Cu" "F.Mask" "F.Paste")
			(net "GND")
		)
		(pad "174" smd rect
			(at 2.050034 -38.675056 270)
			(size 0.519938 1.4986)
			(layers "F.Cu" "F.Mask" "F.Paste")
			(net "M_C_CPU0_SA_DQ<18>")
		)
		(pad "175" smd rect
			(at 2.050034 -37.824918 270)
			(size 0.519938 1.4986)
			(layers "F.Cu" "F.Mask" "F.Paste")
			(net "GND")
		)
		(pad "176" smd rect
			(at 2.050034 -36.975034 270)
			(size 0.519938 1.4986)
			(layers "F.Cu" "F.Mask" "F.Paste")
			(net "M_C_CPU0_SA_DQ<19>")
		)
		(pad "177" smd rect
			(at 2.050034 -36.124896 270)
			(size 0.519938 1.4986)
			(layers "F.Cu" "F.Mask" "F.Paste")
			(net "GND")
		)
		(pad "178" smd rect
			(at 2.050034 -35.275012 270)
			(size 0.519938 1.4986)
			(layers "F.Cu" "F.Mask" "F.Paste")
			(net "M_C_CPU0_SA_DQS_DN<7>")
		)
		(pad "179" smd rect
			(at 2.050034 -34.425128 270)
			(size 0.519938 1.4986)
			(layers "F.Cu" "F.Mask" "F.Paste")
			(net "M_C_CPU0_SA_DQS_DP<7>")
		)
		(pad "180" smd rect
			(at 2.050034 -33.57499 270)
			(size 0.519938 1.4986)
			(layers "F.Cu" "F.Mask" "F.Paste")
			(net "GND")
		)
		(pad "181" smd rect
			(at 2.050034 -32.725106 270)
			(size 0.519938 1.4986)
			(layers "F.Cu" "F.Mask" "F.Paste")
			(net "M_C_CPU0_SA_DQ<22>")
		)
		(pad "182" smd rect
			(at 2.050034 -31.874968 270)
			(size 0.519938 1.4986)
			(layers "F.Cu" "F.Mask" "F.Paste")
			(net "GND")
		)
	)
)
